FILE_TYPE=LIBRARY_PARTS;
primitive 'AP2205W57';
  pin
    'VOUT':
      PIN_NUMBER='(5)';
      PINUSE='POWER';
      NO_LOAD_CHECK='Both';
      NO_IO_CHECK='Both';
      NO_ASSERT_CHECK='TRUE';
      NO_DIR_CHECK='TRUE';
      ALLOW_CONNECT='TRUE';
    'ADJ||NC':
      PIN_NUMBER='(4)';
      BIDIRECTIONAL='TRUE';
      INPUT_LOAD='(-0.01,0.01)';
      OUTPUT_LOAD='(1.0,-1.0)';
    'VIN':
      PIN_NUMBER='(1)';
      PINUSE='POWER';
      NO_LOAD_CHECK='Both';
      NO_IO_CHECK='Both';
      NO_ASSERT_CHECK='TRUE';
      NO_DIR_CHECK='TRUE';
      ALLOW_CONNECT='TRUE';
    'GND':
      PIN_NUMBER='(2)';
      PINUSE='POWER';
      NO_LOAD_CHECK='Both';
      NO_IO_CHECK='Both';
      NO_ASSERT_CHECK='TRUE';
      NO_DIR_CHECK='TRUE';
      ALLOW_CONNECT='TRUE';
    'EN':
      PIN_NUMBER='(3)';
      INPUT_LOAD='(-0.01,0.01)';
  end_pin;
  body
    PART_NAME='AP2205W57';
    BODY_NAME='AP2205W57';
    PHYS_DES_PREFIX='U';
    CLASS='IC';
  end_body;
end_primitive;

END.
